FILE_TYPE = CONNECTIVITY;
{Allegro Design Entry HDL 17.4-2019 S026 (4007227) 1/17/2022}
"PAGE_NUMBER" = 442;
0"NC";
1"GND\g";
2"GND\g";
3"GND\g";
4"GND\g";
5"SMB_RT_CPU1_P1_ROM_R_SDA";
6"SMB_RT_CPU1_P1_ROM_SDA";
7"SMB_RT_CPU1_P1_ROM_R_SCL";
8"SMB_RT_CPU1_P1_ROM_SCL";
9"U19_E2";
10"P1V8_CPU1_RT_1D\g";
%"UNIVERSAL_GND"
"1","(-3025,4850)","0","pure_quanta_power","I18";
;
CDS_LIB"pure_quanta_power"
HDL_POWER"GND";
"A"1;
%"Q_RES"
"2","(-2875,4900)","0","pure_quanta","I19";
;
LOCATION"R6789"
$SEC"1"
CDS_SEC"1"
WATTAGE"1/20W"
TOLERANCE"1%"
VALUE"1K"
PACK_TYPE"0201LF"
MATERIAL"CHIP"
CDS_LIB"pure_quanta"
PART_NUMBER"CS21001FE07";
"A"
$PN"1"9;
"B"
$PN"2"2;
%"UNIVERSAL_GND"
"1","(-2875,4625)","0","pure_quanta_power","I20";
;
CDS_LIB"pure_quanta_power"
HDL_POWER"GND";
"A"2;
%"P1V0"
"1","(-4325,5875)","0","pure_quanta_power","I21";
;
HDL_POWER"P1V8_CPU1_RT_1D"
CDS_LIB"pure_quanta_power";
"A"10;
%"Q_CAP"
"1","(-4600,5625)","0","pure_quanta","I22";
;
LOCATION"C7502"
$SEC"1"
CDS_SEC"1"
VOLTAGE"10V"
PACK_TYPE"C0201"
TOLERANCE"10%"
MATERIAL"X7S"
VALUE"0.1UF"
CDS_LIB"pure_quanta"
PART_NUMBER"CH4102K6E00";
"B"
$PN"2"3;
"A"
$PN"1"10;
%"UNIVERSAL_GND"
"1","(-4600,5325)","0","pure_quanta_power","I23";
;
CDS_LIB"pure_quanta_power"
HDL_POWER"GND";
"A"3;
%"UNIVERSAL_GND"
"1","(-4325,5125)","7","pure_quanta_power","I24";
;
CDS_LIB"pure_quanta_power"
HDL_POWER"GND";
"A"4;
%"Q_RES"
"1","(-5275,5025)","0","pure_quanta","I3";
;
LOCATION"R690"
$SEC"1"
CDS_SEC"1"
PACK_TYPE"0201LF"
WATTAGE"1/20W"
MATERIAL"CHIP"
CDS_LIB"pure_quanta"
VALUE"33.2"
TOLERANCE"1%"
PART_NUMBER"CS03321FE09";
"B"
$PN"2"6;
"A"
$PN"1"5;
%"Q_RES"
"1","(-5275,5075)","0","pure_quanta","I4";
;
LOCATION"R689"
$SEC"1"
CDS_SEC"1"
WATTAGE"1/20W"
MATERIAL"CHIP"
PACK_TYPE"0201LF"
VALUE"33.2"
TOLERANCE"1%"
CDS_LIB"pure_quanta"
PART_NUMBER"CS03321FE09";
"B"
$PN"2"8;
"A"
$PN"1"7;
%"M24M02DRMN6TP"
"1","(-3850,5100)","0","pure_quanta","I5";
;
LOCATION"U19"
$SEC"1"
CDS_SEC"1"
PART_TYPE"SMLF"
MATERIAL"IC"
VALUE"M24M02-DRMN6TP"
CDS_LIB"pure_quanta"
CDS_LMAN_SYM_OUTLINE"-175,125,175,-125"
NEEDS_NO_SIZE"TRUE"
PART_NUMBER"AKE33Z00600";
"DU1"
$PN"1"0;
"DU2"
$PN"2"0;
"E2"
$PN"3"9;
"VSS"
$PN"4"1;
"SDA"
$PN"5"6;
"SCL"
$PN"6"8;
"WC_N \B"
$PN"7"4;
"VCC"
$PN"8"10;
END.
